(kicad_pcb
	(version 20260206)
	(generator "pcbnew")
	(generator_version "10.0")
	(general
		(thickness 1.6)
		(legacy_teardrops no)
	)
	(paper "A4")
	(title_block
		(title "peb — Lightning_PEB_BRD.brd")
		(comment 1 "Lightning (Wiwynn / Facebook NVMe JBOF) / footprint 1064 of 2563 (GF10), pads 1-113 of 200")
	)
	(layers
		(0 "F.Cu" signal "TOP")
		(4 "In1.Cu" signal "L2GND")
		(6 "In2.Cu" signal "L3")
		(8 "In3.Cu" signal "L4VCC")
		(10 "In4.Cu" signal "L5VCC")
		(12 "In5.Cu" signal "L6")
		(14 "In6.Cu" signal "L7GND")
		(2 "B.Cu" signal "BOTTOM")
		(9 "F.Adhes" user "F.Adhesive")
		(11 "B.Adhes" user "B.Adhesive")
		(13 "F.Paste" user "Package Geometry/Pastemask Top")
		(15 "B.Paste" user "Package Geometry/Pastemask Bottom")
		(5 "F.SilkS" user "Ref Des/Silkscreen Top")
		(7 "B.SilkS" user "Ref Des/Silkscreen Bottom")
		(1 "F.Mask" user "Board Geometry/Soldermask Top")
		(3 "B.Mask" user "Board Geometry/Soldermask Bottom")
		(17 "Dwgs.User" user "User.Drawings")
		(19 "Cmts.User" user "User.Comments")
		(21 "Eco1.User" user "User.Eco1")
		(23 "Eco2.User" user "User.Eco2")
		(25 "Edge.Cuts" user "Board Geometry/Outline")
		(27 "Margin" user)
		(31 "F.CrtYd" user "Package Geometry/Place Bound Top")
		(29 "B.CrtYd" user "Package Geometry/Place Bound Bottom")
		(35 "F.Fab" user "Ref Des/Assembly Top")
		(33 "B.Fab" user "Ref Des/Assembly Bottom")
	)
	(footprint ""
		(layer "F.Cu")
		(at 307.300122 -226.70008 180)
		(property "Reference" "GF10"
			(at 0 0 180)
			(layer "F.SilkS")
			(hide yes)
			(effects
				(font
					(size 1.27 1.27)
				)
			)
		)
		(property "Value" "GF-200P-8-GP-U1"
			(at -43.1673 -7.6327 180)
			(unlocked yes)
			(layer "F.Fab")
			(hide yes)
			(effects
				(font
					(size 1.016 1.016)
					(thickness 0.1524)
				)
			)
		)
		(property "Device Type" "GF-200P-8-U1"
			(at -43.1673 -9.1567 180)
			(unlocked yes)
			(layer "F.Fab")
			(hide yes)
			(effects
				(font
					(size 1.016 1.016)
					(thickness 0.1524)
				)
			)
		)
		(duplicate_pad_numbers_are_jumpers no)
		(pad "A1" smd rect
			(at -36.399978 -1.1557 180)
			(size 0.5588 2.3114)
			(layers "F.Cu" "F.Mask" "F.Paste")
			(net "GND")
		)
		(pad "A2" smd rect
			(at -35.599878 -1.1557 180)
			(size 0.5588 2.3114)
			(layers "F.Cu" "F.Mask" "F.Paste")
			(net "PCIE_TX_N16")
		)
		(pad "A3" smd rect
			(at -34.800032 -1.1557 180)
			(size 0.5588 2.3114)
			(layers "F.Cu" "F.Mask" "F.Paste")
			(net "PCIE_TX_P16")
		)
		(pad "A4" smd rect
			(at -33.999932 -1.1557 180)
			(size 0.5588 2.3114)
			(layers "F.Cu" "F.Mask" "F.Paste")
			(net "GND")
		)
		(pad "A5" smd rect
			(at -33.200086 -1.1557 180)
			(size 0.5588 2.3114)
			(layers "F.Cu" "F.Mask" "F.Paste")
			(net "GND")
		)
		(pad "A6" smd rect
			(at -32.399986 -1.1557 180)
			(size 0.5588 2.3114)
			(layers "F.Cu" "F.Mask" "F.Paste")
			(net "PCIE_TX_N17")
		)
		(pad "A7" smd rect
			(at -31.599886 -1.1557 180)
			(size 0.5588 2.3114)
			(layers "F.Cu" "F.Mask" "F.Paste")
			(net "PCIE_TX_P17")
		)
		(pad "A8" smd rect
			(at -30.80004 -1.1557 180)
			(size 0.5588 2.3114)
			(layers "F.Cu" "F.Mask" "F.Paste")
			(net "GND")
		)
		(pad "A9" smd rect
			(at -29.99994 -1.1557 180)
			(size 0.5588 2.3114)
			(layers "F.Cu" "F.Mask" "F.Paste")
			(net "GND")
		)
		(pad "A10" smd rect
			(at -29.200094 -1.1557 180)
			(size 0.5588 2.3114)
			(layers "F.Cu" "F.Mask" "F.Paste")
			(net "PCIE_TX_N18")
		)
		(pad "A11" smd rect
			(at -28.399994 -1.1557 180)
			(size 0.5588 2.3114)
			(layers "F.Cu" "F.Mask" "F.Paste")
			(net "PCIE_TX_P18")
		)
		(pad "A12" smd rect
			(at -27.599894 -1.1557 180)
			(size 0.5588 2.3114)
			(layers "F.Cu" "F.Mask" "F.Paste")
			(net "GND")
		)
		(pad "A13" smd rect
			(at -26.800048 -1.1557 180)
			(size 0.5588 2.3114)
			(layers "F.Cu" "F.Mask" "F.Paste")
			(net "GND")
		)
		(pad "A14" smd rect
			(at -25.999948 -1.1557 180)
			(size 0.5588 2.3114)
			(layers "F.Cu" "F.Mask" "F.Paste")
			(net "PCIE_TX_N19")
		)
		(pad "A15" smd rect
			(at -25.200102 -1.1557 180)
			(size 0.5588 2.3114)
			(layers "F.Cu" "F.Mask" "F.Paste")
			(net "PCIE_TX_P19")
		)
		(pad "A16" smd rect
			(at -24.400002 -1.1557 180)
			(size 0.5588 2.3114)
			(layers "F.Cu" "F.Mask" "F.Paste")
			(net "GND")
		)
		(pad "A17" smd rect
			(at -23.599902 -1.1557 180)
			(size 0.5588 2.3114)
			(layers "F.Cu" "F.Mask" "F.Paste")
			(net "SSD_PRSNT#14_R")
		)
		(pad "A18" smd rect
			(at -22.800056 -1.1557 180)
			(size 0.5588 2.3114)
			(layers "F.Cu" "F.Mask" "F.Paste")
			(net "SSD_PWREN9_R")
		)
		(pad "A19" smd rect
			(at -21.999956 -1.1557 180)
			(size 0.5588 2.3114)
			(layers "F.Cu" "F.Mask" "F.Paste")
			(net "SSD_ATNLED#9_R")
		)
		(pad "A20" smd rect
			(at -21.20011 -1.1557 180)
			(size 0.5588 2.3114)
			(layers "F.Cu" "F.Mask" "F.Paste")
			(net "SSD_PRSNT#9_R")
		)
		(pad "A21" smd rect
			(at -20.40001 -1.1557 180)
			(size 0.5588 2.3114)
			(layers "F.Cu" "F.Mask" "F.Paste")
			(net "GND")
		)
		(pad "A22" smd rect
			(at -19.59991 -1.1557 180)
			(size 0.5588 2.3114)
			(layers "F.Cu" "F.Mask" "F.Paste")
			(net "PCIE_TX_N20")
		)
		(pad "A23" smd rect
			(at -18.800064 -1.1557 180)
			(size 0.5588 2.3114)
			(layers "F.Cu" "F.Mask" "F.Paste")
			(net "PCIE_TX_P20")
		)
		(pad "A24" smd rect
			(at -17.999964 -1.1557 180)
			(size 0.5588 2.3114)
			(layers "F.Cu" "F.Mask" "F.Paste")
			(net "GND")
		)
		(pad "A25" smd rect
			(at -17.200118 -1.1557 180)
			(size 0.5588 2.3114)
			(layers "F.Cu" "F.Mask" "F.Paste")
			(net "GND")
		)
		(pad "A26" smd rect
			(at -16.400018 -1.1557 180)
			(size 0.5588 2.3114)
			(layers "F.Cu" "F.Mask" "F.Paste")
			(net "PCIE_TX_N21")
		)
		(pad "A27" smd rect
			(at -15.599918 -1.1557 180)
			(size 0.5588 2.3114)
			(layers "F.Cu" "F.Mask" "F.Paste")
			(net "PCIE_TX_P21")
		)
		(pad "A28" smd rect
			(at -14.800072 -1.1557 180)
			(size 0.5588 2.3114)
			(layers "F.Cu" "F.Mask" "F.Paste")
			(net "GND")
		)
		(pad "A29" smd rect
			(at -13.999972 -1.1557 180)
			(size 0.5588 2.3114)
			(layers "F.Cu" "F.Mask" "F.Paste")
			(net "GND")
		)
		(pad "A30" smd rect
			(at -13.200126 -1.1557 180)
			(size 0.5588 2.3114)
			(layers "F.Cu" "F.Mask" "F.Paste")
			(net "PCIE_TX_N22")
		)
		(pad "A31" smd rect
			(at -12.400026 -1.1557 180)
			(size 0.5588 2.3114)
			(layers "F.Cu" "F.Mask" "F.Paste")
			(net "PCIE_TX_P22")
		)
		(pad "A32" smd rect
			(at -11.599926 -1.1557 180)
			(size 0.5588 2.3114)
			(layers "F.Cu" "F.Mask" "F.Paste")
			(net "GND")
		)
		(pad "A33" smd rect
			(at -10.80008 -1.1557 180)
			(size 0.5588 2.3114)
			(layers "F.Cu" "F.Mask" "F.Paste")
			(net "GND")
		)
		(pad "A34" smd rect
			(at -9.99998 -1.1557 180)
			(size 0.5588 2.3114)
			(layers "F.Cu" "F.Mask" "F.Paste")
			(net "PCIE_TX_N23")
		)
		(pad "A35" smd rect
			(at -9.19988 -1.1557 180)
			(size 0.5588 2.3114)
			(layers "F.Cu" "F.Mask" "F.Paste")
			(net "PCIE_TX_P23")
		)
		(pad "A36" smd rect
			(at -8.400034 -1.1557 180)
			(size 0.5588 2.3114)
			(layers "F.Cu" "F.Mask" "F.Paste")
			(net "GND")
		)
		(pad "A37" smd rect
			(at -7.599934 -1.1557 180)
			(size 0.5588 2.3114)
			(layers "F.Cu" "F.Mask" "F.Paste")
			(net "GND")
		)
		(pad "A38" smd rect
			(at -6.800088 -1.1557 180)
			(size 0.5588 2.3114)
			(layers "F.Cu" "F.Mask" "F.Paste")
			(net "PCIE_TX_N24")
		)
		(pad "A39" smd rect
			(at -5.999988 -1.1557 180)
			(size 0.5588 2.3114)
			(layers "F.Cu" "F.Mask" "F.Paste")
			(net "PCIE_TX_P24")
		)
		(pad "A40" smd rect
			(at -5.199888 -1.1557 180)
			(size 0.5588 2.3114)
			(layers "F.Cu" "F.Mask" "F.Paste")
			(net "GND")
		)
		(pad "A41" smd rect
			(at -4.400042 -1.1557 180)
			(size 0.5588 2.3114)
			(layers "F.Cu" "F.Mask" "F.Paste")
			(net "GND")
		)
		(pad "A42" smd rect
			(at -3.599942 -1.1557 180)
			(size 0.5588 2.3114)
			(layers "F.Cu" "F.Mask" "F.Paste")
			(net "PCIE_TX_N25")
		)
		(pad "A43" smd rect
			(at -2.800096 -1.1557 180)
			(size 0.5588 2.3114)
			(layers "F.Cu" "F.Mask" "F.Paste")
			(net "PCIE_TX_P25")
		)
		(pad "A44" smd rect
			(at -1.999996 -1.1557 180)
			(size 0.5588 2.3114)
			(layers "F.Cu" "F.Mask" "F.Paste")
			(net "GND")
		)
		(pad "A45" smd rect
			(at 1.999996 -1.1557 180)
			(size 0.5588 2.3114)
			(layers "F.Cu" "F.Mask" "F.Paste")
			(net "SSD_PERST#9_R")
		)
		(pad "A46" smd rect
			(at 2.800096 -1.1557 180)
			(size 0.5588 1.8796)
			(drill
				(offset 0 -0.2159)
			)
			(layers "F.Cu" "F.Mask" "F.Paste")
			(net "SSD_PERST#13_R")
		)
		(pad "A47" smd rect
			(at 3.599942 -1.1557 180)
			(size 0.5588 2.3114)
			(layers "F.Cu" "F.Mask" "F.Paste")
			(net "GND")
		)
		(pad "A48" smd rect
			(at 4.400042 -1.1557 180)
			(size 0.5588 2.3114)
			(layers "F.Cu" "F.Mask" "F.Paste")
			(net "PCIE_TX_N26")
		)
		(pad "A49" smd rect
			(at 5.199888 -1.1557 180)
			(size 0.5588 2.3114)
			(layers "F.Cu" "F.Mask" "F.Paste")
			(net "PCIE_TX_P26")
		)
		(pad "A50" smd rect
			(at 5.999988 -1.1557 180)
			(size 0.5588 2.3114)
			(layers "F.Cu" "F.Mask" "F.Paste")
			(net "GND")
		)
		(pad "A51" smd rect
			(at 6.800088 -1.1557 180)
			(size 0.5588 2.3114)
			(layers "F.Cu" "F.Mask" "F.Paste")
			(net "GND")
		)
		(pad "A52" smd rect
			(at 7.599934 -1.1557 180)
			(size 0.5588 2.3114)
			(layers "F.Cu" "F.Mask" "F.Paste")
			(net "PCIE_TX_N27")
		)
		(pad "A53" smd rect
			(at 8.400034 -1.1557 180)
			(size 0.5588 2.3114)
			(layers "F.Cu" "F.Mask" "F.Paste")
			(net "PCIE_TX_P27")
		)
		(pad "A54" smd rect
			(at 9.19988 -1.1557 180)
			(size 0.5588 2.3114)
			(layers "F.Cu" "F.Mask" "F.Paste")
			(net "GND")
		)
		(pad "A55" smd rect
			(at 9.99998 -1.1557 180)
			(size 0.5588 2.3114)
			(layers "F.Cu" "F.Mask" "F.Paste")
			(net "SSD_PWREN13_R")
		)
		(pad "A56" smd rect
			(at 10.80008 -1.1557 180)
			(size 0.5588 2.3114)
			(layers "F.Cu" "F.Mask" "F.Paste")
			(net "SSD_ATNLED#13_R")
		)
		(pad "A57" smd rect
			(at 11.599926 -1.1557 180)
			(size 0.5588 2.3114)
			(layers "F.Cu" "F.Mask" "F.Paste")
			(net "SSD_PRSNT#13_R")
		)
		(pad "A58" smd rect
			(at 12.400026 -1.1557 180)
			(size 0.5588 2.3114)
			(layers "F.Cu" "F.Mask" "F.Paste")
			(net "GND")
		)
		(pad "A59" smd rect
			(at 13.200126 -1.1557 180)
			(size 0.5588 2.3114)
			(layers "F.Cu" "F.Mask" "F.Paste")
			(net "PCIE_TX_N28")
		)
		(pad "A60" smd rect
			(at 13.999972 -1.1557 180)
			(size 0.5588 2.3114)
			(layers "F.Cu" "F.Mask" "F.Paste")
			(net "PCIE_TX_P28")
		)
		(pad "A61" smd rect
			(at 14.800072 -1.1557 180)
			(size 0.5588 2.3114)
			(layers "F.Cu" "F.Mask" "F.Paste")
			(net "GND")
		)
		(pad "A62" smd rect
			(at 15.599918 -1.1557 180)
			(size 0.5588 2.3114)
			(layers "F.Cu" "F.Mask" "F.Paste")
			(net "GND")
		)
		(pad "A63" smd rect
			(at 16.400018 -1.1557 180)
			(size 0.5588 2.3114)
			(layers "F.Cu" "F.Mask" "F.Paste")
			(net "PCIE_TX_N29")
		)
		(pad "A64" smd rect
			(at 17.200118 -1.1557 180)
			(size 0.5588 2.3114)
			(layers "F.Cu" "F.Mask" "F.Paste")
			(net "PCIE_TX_P29")
		)
		(pad "A65" smd rect
			(at 17.999964 -1.1557 180)
			(size 0.5588 2.3114)
			(layers "F.Cu" "F.Mask" "F.Paste")
			(net "GND")
		)
		(pad "A66" smd rect
			(at 18.800064 -1.1557 180)
			(size 0.5588 2.3114)
			(layers "F.Cu" "F.Mask" "F.Paste")
			(net "GND")
		)
		(pad "A67" smd rect
			(at 19.59991 -1.1557 180)
			(size 0.5588 2.3114)
			(layers "F.Cu" "F.Mask" "F.Paste")
			(net "PCIE_TX_N30")
		)
		(pad "A68" smd rect
			(at 20.40001 -1.1557 180)
			(size 0.5588 2.3114)
			(layers "F.Cu" "F.Mask" "F.Paste")
			(net "PCIE_TX_P30")
		)
		(pad "A69" smd rect
			(at 21.20011 -1.1557 180)
			(size 0.5588 2.3114)
			(layers "F.Cu" "F.Mask" "F.Paste")
			(net "GND")
		)
		(pad "A70" smd rect
			(at 21.999956 -1.1557 180)
			(size 0.5588 2.3114)
			(layers "F.Cu" "F.Mask" "F.Paste")
			(net "GND")
		)
		(pad "A71" smd rect
			(at 22.800056 -1.1557 180)
			(size 0.5588 2.3114)
			(layers "F.Cu" "F.Mask" "F.Paste")
			(net "PCIE_TX_N31")
		)
		(pad "A72" smd rect
			(at 23.599902 -1.1557 180)
			(size 0.5588 2.3114)
			(layers "F.Cu" "F.Mask" "F.Paste")
			(net "PCIE_TX_P31")
		)
		(pad "A73" smd rect
			(at 24.400002 -1.1557 180)
			(size 0.5588 2.3114)
			(layers "F.Cu" "F.Mask" "F.Paste")
			(net "GND")
		)
		(pad "A74" smd rect
			(at 25.200102 -1.1557 180)
			(size 0.5588 2.3114)
			(layers "F.Cu" "F.Mask" "F.Paste")
			(net "GND")
		)
		(pad "A75" smd rect
			(at 25.999948 -1.1557 180)
			(size 0.5588 2.3114)
			(layers "F.Cu" "F.Mask" "F.Paste")
			(net "PCIE_TX_N32")
		)
		(pad "A76" smd rect
			(at 26.800048 -1.1557 180)
			(size 0.5588 2.3114)
			(layers "F.Cu" "F.Mask" "F.Paste")
			(net "PCIE_TX_P32")
		)
		(pad "A77" smd rect
			(at 27.599894 -1.1557 180)
			(size 0.5588 2.3114)
			(layers "F.Cu" "F.Mask" "F.Paste")
			(net "GND")
		)
		(pad "A78" smd rect
			(at 28.399994 -1.1557 180)
			(size 0.5588 2.3114)
			(layers "F.Cu" "F.Mask" "F.Paste")
			(net "GND")
		)
		(pad "A79" smd rect
			(at 29.200094 -1.1557 180)
			(size 0.5588 2.3114)
			(layers "F.Cu" "F.Mask" "F.Paste")
			(net "PCIE_TX_N33")
		)
		(pad "A80" smd rect
			(at 29.99994 -1.1557 180)
			(size 0.5588 2.3114)
			(layers "F.Cu" "F.Mask" "F.Paste")
			(net "PCIE_TX_P33")
		)
		(pad "A81" smd rect
			(at 30.80004 -1.1557 180)
			(size 0.5588 2.3114)
			(layers "F.Cu" "F.Mask" "F.Paste")
			(net "GND")
		)
		(pad "A82" smd rect
			(at 31.599886 -1.1557 180)
			(size 0.5588 2.3114)
			(layers "F.Cu" "F.Mask" "F.Paste")
			(net "GND")
		)
		(pad "A83" smd rect
			(at 32.399986 -1.1557 180)
			(size 0.5588 2.3114)
			(layers "F.Cu" "F.Mask" "F.Paste")
			(net "PCIE_TX_N34")
		)
		(pad "A84" smd rect
			(at 33.200086 -1.1557 180)
			(size 0.5588 2.3114)
			(layers "F.Cu" "F.Mask" "F.Paste")
			(net "PCIE_TX_P34")
		)
		(pad "A85" smd rect
			(at 33.999932 -1.1557 180)
			(size 0.5588 2.3114)
			(layers "F.Cu" "F.Mask" "F.Paste")
			(net "GND")
		)
		(pad "A86" smd rect
			(at 34.800032 -1.1557 180)
			(size 0.5588 2.3114)
			(layers "F.Cu" "F.Mask" "F.Paste")
			(net "GND")
		)
		(pad "A87" smd rect
			(at 35.599878 -1.1557 180)
			(size 0.5588 2.3114)
			(layers "F.Cu" "F.Mask" "F.Paste")
			(net "PCIE_TX_N35")
		)
		(pad "A88" smd rect
			(at 36.399978 -1.1557 180)
			(size 0.5588 2.3114)
			(layers "F.Cu" "F.Mask" "F.Paste")
			(net "PCIE_TX_P35")
		)
		(pad "A89" smd rect
			(at 37.200078 -1.1557 180)
			(size 0.5588 2.3114)
			(layers "F.Cu" "F.Mask" "F.Paste")
			(net "GND")
		)
		(pad "A90" smd rect
			(at 37.999924 -1.1557 180)
			(size 0.5588 2.3114)
			(layers "F.Cu" "F.Mask" "F.Paste")
			(net "GND")
		)
		(pad "A91" smd rect
			(at 38.800024 -1.1557 180)
			(size 0.5588 2.3114)
			(layers "F.Cu" "F.Mask" "F.Paste")
			(net "PCIE_TX_N36")
		)
		(pad "A92" smd rect
			(at 39.600124 -1.1557 180)
			(size 0.5588 2.3114)
			(layers "F.Cu" "F.Mask" "F.Paste")
			(net "PCIE_TX_P36")
		)
		(pad "A93" smd rect
			(at 40.39997 -1.1557 180)
			(size 0.5588 2.3114)
			(layers "F.Cu" "F.Mask" "F.Paste")
			(net "GND")
		)
		(pad "A94" smd rect
			(at 41.20007 -1.1557 180)
			(size 0.5588 2.3114)
			(layers "F.Cu" "F.Mask" "F.Paste")
			(net "GND")
		)
		(pad "A95" smd rect
			(at 41.999916 -1.1557 180)
			(size 0.5588 2.3114)
			(layers "F.Cu" "F.Mask" "F.Paste")
			(net "PCIE_TX_N37")
		)
		(pad "A96" smd rect
			(at 42.800016 -1.1557 180)
			(size 0.5588 2.3114)
			(layers "F.Cu" "F.Mask" "F.Paste")
			(net "PCIE_TX_P37")
		)
		(pad "A97" smd rect
			(at 43.600116 -1.1557 180)
			(size 0.5588 2.3114)
			(layers "F.Cu" "F.Mask" "F.Paste")
			(net "GND")
		)
		(pad "A98" smd rect
			(at 44.399962 -1.1557 180)
			(size 0.5588 2.3114)
			(layers "F.Cu" "F.Mask" "F.Paste")
			(net "EXP_TRAY_ID")
		)
		(pad "A99" smd rect
			(at 45.200062 -1.1557 180)
			(size 0.5588 2.3114)
			(layers "F.Cu" "F.Mask" "F.Paste")
			(net "SHUTDOWN_RELEASE")
		)
		(pad "A100" smd rect
			(at 45.999908 -1.1557 180)
			(size 0.5588 1.8796)
			(drill
				(offset 0 -0.2159)
			)
			(layers "F.Cu" "F.Mask" "F.Paste")
			(net "PCIE_MATED#_B")
		)
		(pad "B1" smd rect
			(at -36.399978 -0.7747 180)
			(size 0.5588 2.3114)
			(drill
				(offset 0 -0.381)
			)
			(layers "F.Cu" "F.Mask" "F.Paste")
			(net "SSD_ATNLED#14_R")
		)
		(pad "B2" smd rect
			(at -35.599878 -0.7747 180)
			(size 0.5588 2.3114)
			(drill
				(offset 0 -0.381)
			)
			(layers "F.Cu" "F.Mask" "F.Paste")
			(net "SSD_PWREN14_R")
		)
		(pad "B3" smd rect
			(at -34.800032 -0.7747 180)
			(size 0.5588 2.3114)
			(drill
				(offset 0 -0.381)
			)
			(layers "F.Cu" "F.Mask" "F.Paste")
			(net "GND")
		)
		(pad "B4" smd rect
			(at -33.999932 -0.7747 180)
			(size 0.5588 2.3114)
			(drill
				(offset 0 -0.381)
			)
			(layers "F.Cu" "F.Mask" "F.Paste")
			(net "PCIE_RX_N16")
		)
		(pad "B5" smd rect
			(at -33.200086 -0.7747 180)
			(size 0.5588 2.3114)
			(drill
				(offset 0 -0.381)
			)
			(layers "F.Cu" "F.Mask" "F.Paste")
			(net "PCIE_RX_P16")
		)
		(pad "B6" smd rect
			(at -32.399986 -0.7747 180)
			(size 0.5588 2.3114)
			(drill
				(offset 0 -0.381)
			)
			(layers "F.Cu" "F.Mask" "F.Paste")
			(net "GND")
		)
		(pad "B7" smd rect
			(at -31.599886 -0.7747 180)
			(size 0.5588 2.3114)
			(drill
				(offset 0 -0.381)
			)
			(layers "F.Cu" "F.Mask" "F.Paste")
			(net "GND")
		)
		(pad "B8" smd rect
			(at -30.80004 -0.7747 180)
			(size 0.5588 2.3114)
			(drill
				(offset 0 -0.381)
			)
			(layers "F.Cu" "F.Mask" "F.Paste")
			(net "PCIE_RX_N17")
		)
		(pad "B9" smd rect
			(at -29.99994 -0.7747 180)
			(size 0.5588 2.3114)
			(drill
				(offset 0 -0.381)
			)
			(layers "F.Cu" "F.Mask" "F.Paste")
			(net "PCIE_RX_P17")
		)
		(pad "B10" smd rect
			(at -29.200094 -0.7747 180)
			(size 0.5588 2.3114)
			(drill
				(offset 0 -0.381)
			)
			(layers "F.Cu" "F.Mask" "F.Paste")
			(net "GND")
		)
		(pad "B11" smd rect
			(at -28.399994 -0.7747 180)
			(size 0.5588 2.3114)
			(drill
				(offset 0 -0.381)
			)
			(layers "F.Cu" "F.Mask" "F.Paste")
			(net "GND")
		)
		(pad "B12" smd rect
			(at -27.599894 -0.7747 180)
			(size 0.5588 2.3114)
			(drill
				(offset 0 -0.381)
			)
			(layers "F.Cu" "F.Mask" "F.Paste")
			(net "PCIE_RX_N18")
		)
		(pad "B13" smd rect
			(at -26.800048 -0.7747 180)
			(size 0.5588 2.3114)
			(drill
				(offset 0 -0.381)
			)
			(layers "F.Cu" "F.Mask" "F.Paste")
			(net "PCIE_RX_P18")
		)
	)
)
